FILE_TYPE = MULTI_PHYS_TABLE;
PART 'SKX_EXT_B'
{=======================================================================================================================================================================================================================}
:PACK_TYPE | MATERIAL | PART_NUMBER     = EnvComp             |  PART_NUMBER  | JEDEC_TYPE        |  DESCRIPTION                                                    | CLASS | COMPONENT_TYPE | HEIGHT     | LPID   | SPEED_URL | Status |RPL| AML | Bus_Unit | Days ;
{=======================================================================================================================================================================================================================}
'BGA'      | 'IC'     | 'TBD'(!)        = ''                  |  'TBD'        | 'XBGA3647_5_P0'   | 'SOCKET_P3647 U-PROC/DUAL SOCKET SKYLAKE EP EX'                 | 'IC'  | 'BGA'          | '0.276 IN' | '2725' | 'http://speed.intel.com:8081/speed/module/pdm/item/pdm_item_detail_direct.asp?item_cde=TBD&item_rev=01&url_param=unused' | '' | '' | '' | '' | '' 
'BGA'      | 'EMPTY'  | 'TBD'(!)        = ''                  |  'TBD'        | 'XBGA3647_5_P0'   | 'SOCKET_P3647 U-PROC/DUAL SOCKET SKYLAKE EP EX'                 | 'IO'  | 'BGA'          | '0.276 IN' | '2725' | 'http://speed.intel.com:8081/speed/module/pdm/item/pdm_item_detail_direct.asp?item_cde=TBD&item_rev=01&url_param=unused' | '' | '' | '' | '' | '' 
'BGA1'     | 'IC'     | 'TBD'(!)        = ''                  |  'TBD'        | 'XBGA3647_5_P0B'  | 'SOCKET_P3647 U-PROC/DUAL SOCKET SKYLAKE EP EX PAD CHANGES'     | 'IC'  | 'BGA'          | '0.276 IN' | '2725' | 'http://speed.intel.com:8081/speed/module/pdm/item/pdm_item_detail_direct.asp?item_cde=TBD&item_rev=01&url_param=unused' | '' | '' | '' | '' | '' 
'BGA1'     | 'EMPTY'  | 'TBD'(!)        = ''                  |  'TBD'        | 'XBGA3647_5_P0B'  | 'SOCKET_P3647 U-PROC/DUAL SOCKET SKYLAKE EP EX PAD CHANGES'     | 'IO'  | 'BGA'          | '0.276 IN' | '2725' | 'http://speed.intel.com:8081/speed/module/pdm/item/pdm_item_detail_direct.asp?item_cde=TBD&item_rev=01&url_param=unused' | '' | '' | '' | '' | '' 
'INT'      | 'EMPTY'  | 'NA'(!)         = ''                  |  'NA'         | 'XBGA3647_5_P0I'  | 'INTERPOSER FOR SOCKET_P3647 U-PROC/DUAL SOCKET SKYLAKE EP EX'  | 'IO'  | 'BGA'          | '0.041 IN' | 'NA'   | 'http://speed.intel.com:8081/speed/module/pdm/item/pdm_item_detail_direct.asp?item_cde=NA&item_rev=01&url_param=unused' | '' | '' | '' | '' | '' 
END_PART
END.
